(kicad_pcb
	(version 20260206)
	(generator "pcbnew")
	(generator_version "10.0")
	(general
		(thickness 1.6)
		(legacy_teardrops no)
	)
	(paper "A4")
	(title_block
		(title "panther-plus-userver — 13130-1b_20150205.brd")
		(comment 1 "Honey Badger (Wiwynn) / footprints 485-491 of 1509")
	)
	(layers
		(0 "F.Cu" signal "TOP")
		(4 "In1.Cu" signal "L2")
		(6 "In2.Cu" signal "L3")
		(8 "In3.Cu" signal "L4")
		(10 "In4.Cu" signal "L5")
		(12 "In5.Cu" signal "L6")
		(14 "In6.Cu" signal "L7")
		(16 "In7.Cu" signal "L8")
		(18 "In8.Cu" signal "L9")
		(20 "In9.Cu" signal "L10")
		(22 "In10.Cu" signal "L11")
		(2 "B.Cu" signal "BOTTOM")
		(9 "F.Adhes" user "F.Adhesive")
		(11 "B.Adhes" user "B.Adhesive")
		(13 "F.Paste" user "Package Geometry/Pastemask Top")
		(15 "B.Paste" user "Package Geometry/Pastemask Bottom")
		(5 "F.SilkS" user "Ref Des/Silkscreen Top")
		(7 "B.SilkS" user "Ref Des/Silkscreen Bottom")
		(1 "F.Mask" user "Board Geometry/Soldermask Top")
		(3 "B.Mask" user "Board Geometry/Soldermask Bottom")
		(17 "Dwgs.User" user "User.Drawings")
		(19 "Cmts.User" user "User.Comments")
		(21 "Eco1.User" user "User.Eco1")
		(23 "Eco2.User" user "User.Eco2")
		(25 "Edge.Cuts" user "Board Geometry/Outline")
		(27 "Margin" user)
		(31 "F.CrtYd" user "Package Geometry/Place Bound Top")
		(29 "B.CrtYd" user "Package Geometry/Place Bound Bottom")
		(35 "F.Fab" user "Ref Des/Assembly Top")
		(33 "B.Fab" user "Ref Des/Assembly Bottom")
	)
	(footprint ""
		(layer "F.Cu")
		(at 148.844 -54.7116 90)
		(property "Reference" "U48"
			(at 0 0 90)
			(layer "F.SilkS")
			(hide yes)
			(effects
				(font
					(size 1.27 1.27)
				)
			)
		)
		(property "Value" "SC18IS602BIPW-GP"
			(at -4.0259 -0.4572 90)
			(unlocked yes)
			(layer "F.Fab")
			(hide yes)
			(effects
				(font
					(size 1.016 1.016)
					(thickness 0.1524)
				)
			)
		)
		(property "Device Type" "TSOIC16H44"
			(at -4.0259 -1.9812 90)
			(unlocked yes)
			(layer "F.Fab")
			(hide yes)
			(effects
				(font
					(size 1.016 1.016)
					(thickness 0.1524)
				)
			)
		)
		(duplicate_pad_numbers_are_jumpers no)
		(fp_line
			(start 2.37617 -1.778)
			(end 2.37617 1.778)
			(stroke
				(width 0.1524)
				(type default)
			)
			(layer "F.SilkS")
		)
		(fp_line
			(start -2.6797 -1.778)
			(end 2.37617 -1.778)
			(stroke
				(width 0.1524)
				(type default)
			)
			(layer "F.SilkS")
		)
		(fp_line
			(start -2.6797 -0.3556)
			(end -2.2987 0.0254)
			(stroke
				(width 0.1524)
				(type default)
			)
			(layer "F.SilkS")
		)
		(fp_line
			(start -2.2987 0.0254)
			(end -2.6797 0.4064)
			(stroke
				(width 0.1524)
				(type default)
			)
			(layer "F.SilkS")
		)
		(fp_line
			(start 2.37617 1.778)
			(end -2.6797 1.778)
			(stroke
				(width 0.1524)
				(type default)
			)
			(layer "F.SilkS")
		)
		(fp_line
			(start -2.6797 1.778)
			(end -2.6797 -1.778)
			(stroke
				(width 0.1524)
				(type default)
			)
			(layer "F.SilkS")
		)
		(fp_line
			(start -2.7305 1.8288)
			(end -2.7305 3.4544)
			(stroke
				(width 0.254)
				(type default)
			)
			(layer "F.SilkS")
		)
		(fp_poly
			(pts
				(xy -2.45237 -1.778) (xy -2.45237 1.778) (xy 2.37617 1.778) (xy 2.37617 -1.778)
			)
			(stroke
				(width 0)
				(type default)
			)
			(fill yes)
			(layer "F.SilkS")
		)
		(fp_rect
			(start -2.7559 3.5814)
			(end 2.7559 -3.5814)
			(stroke
				(width 0)
				(type default)
			)
			(fill no)
			(layer "F.CrtYd")
		)
		(fp_rect
			(start -2.7559 3.5814)
			(end 2.7559 -3.5814)
			(stroke
				(width 0)
				(type default)
			)
			(fill no)
			(layer "F.Fab")
		)
		(pad "1" smd rect
			(at -2.27457 2.7559 90)
			(size 0.3556 1.397)
			(layers "F.Cu" "F.Mask" "F.Paste")
			(net "SPI_SW_CSO#")
		)
		(pad "2" smd rect
			(at -1.6256 2.7559 90)
			(size 0.3556 1.397)
			(layers "F.Cu" "F.Mask" "F.Paste")
			(net "SPI_SW_NCONFIG#")
		)
		(pad "3" smd rect
			(at -0.97536 2.7559 90)
			(size 0.3556 1.397)
			(layers "F.Cu" "F.Mask" "F.Paste")
			(net "SPI_SW_RST#")
		)
		(pad "4" smd rect
			(at -0.32512 2.7559 90)
			(size 0.3556 1.397)
			(layers "F.Cu" "F.Mask" "F.Paste")
			(net "GND")
		)
		(pad "5" smd rect
			(at 0.32512 2.7559 90)
			(size 0.3556 1.397)
			(layers "F.Cu" "F.Mask" "F.Paste")
			(net "SPI_SW_DATA0")
		)
		(pad "6" smd rect
			(at 0.97536 2.7559 90)
			(size 0.3556 1.397)
			(layers "F.Cu" "F.Mask" "F.Paste")
			(net "SPI_SW_ASDO")
		)
		(pad "7" smd rect
			(at 1.6256 2.7559 90)
			(size 0.3556 1.397)
			(layers "F.Cu" "F.Mask" "F.Paste")
			(net "BMC_I2C_DATA")
		)
		(pad "8" smd rect
			(at 2.27457 2.7559 90)
			(size 0.3556 1.397)
			(layers "F.Cu" "F.Mask" "F.Paste")
			(net "BMC_I2C_CLK")
		)
		(pad "9" smd rect
			(at 2.27457 -2.7559 90)
			(size 0.3556 1.397)
			(layers "F.Cu" "F.Mask" "F.Paste")
			(net "SPI_SW_INT#")
		)
		(pad "10" smd rect
			(at 1.6256 -2.7559 90)
			(size 0.3556 1.397)
			(layers "F.Cu" "F.Mask" "F.Paste")
			(net "BUS_SW_SEL")
		)
		(pad "11" smd rect
			(at 0.97536 -2.7559 90)
			(size 0.3556 1.397)
			(layers "F.Cu" "F.Mask" "F.Paste")
			(net "SPI_SW_DCLK")
		)
		(pad "12" smd rect
			(at 0.32512 -2.7559 90)
			(size 0.3556 1.397)
			(layers "F.Cu" "F.Mask" "F.Paste")
			(net "P3V3_STBY")
		)
		(pad "13" smd rect
			(at -0.32512 -2.7559 90)
			(size 0.3556 1.397)
			(layers "F.Cu" "F.Mask" "F.Paste")
			(net "Net_40")
		)
		(pad "14" smd rect
			(at -0.97536 -2.7559 90)
			(size 0.3556 1.397)
			(layers "F.Cu" "F.Mask" "F.Paste")
			(net "SPI_SW_ADDR0")
		)
		(pad "15" smd rect
			(at -1.6256 -2.7559 90)
			(size 0.3556 1.397)
			(layers "F.Cu" "F.Mask" "F.Paste")
			(net "SPI_SW_ADDR1")
		)
		(pad "16" smd rect
			(at -2.27457 -2.7559 90)
			(size 0.3556 1.397)
			(layers "F.Cu" "F.Mask" "F.Paste")
			(net "SPI_SW_ADDR2")
		)
	)
	(footprint ""
		(layer "F.Cu")
		(at 7.2517 -41.9608 180)
		(property "Reference" "PC184"
			(at 0 0 180)
			(layer "F.SilkS")
			(hide yes)
			(effects
				(font
					(size 1.27 1.27)
				)
			)
		)
		(property "Value" "SC22U25V5MX-GP"
			(at 0 -4.9022 180)
			(unlocked yes)
			(layer "F.Fab")
			(hide yes)
			(effects
				(font
					(size 1.016 1.016)
					(thickness 0.1524)
				)
			)
		)
		(property "Device Type" "C805H58"
			(at 0 -6.8072 180)
			(unlocked yes)
			(layer "F.Fab")
			(hide yes)
			(effects
				(font
					(size 1.016 1.016)
					(thickness 0.1524)
				)
			)
		)
		(duplicate_pad_numbers_are_jumpers no)
		(fp_line
			(start 0.6096 0)
			(end -0.6096 0)
			(stroke
				(width 0.3048)
				(type default)
			)
			(layer "F.SilkS")
		)
		(fp_poly
			(pts
				(xy -0.9017 1.4351) (xy 0.9017 1.4351) (xy 0.9017 -1.4351) (xy -0.9017 -1.4351)
			)
			(stroke
				(width 0)
				(type default)
			)
			(fill no)
			(layer "F.CrtYd")
		)
		(fp_poly
			(pts
				(xy 0.9017 1.4351) (xy 0.9017 -1.4351) (xy -0.9017 -1.4351) (xy -0.9017 1.4351)
			)
			(stroke
				(width 0)
				(type default)
			)
			(fill no)
			(layer "F.Fab")
		)
		(pad "1" smd rect
			(at 0 -0.8382 180)
			(size 1.5494 0.9398)
			(layers "F.Cu" "F.Mask" "F.Paste")
			(net "P3V3_STBY_VIN")
		)
		(pad "2" smd rect
			(at 0 0.8382 180)
			(size 1.5494 0.9398)
			(layers "F.Cu" "F.Mask" "F.Paste")
			(net "GND")
		)
	)
	(footprint ""
		(layer "F.Cu")
		(at 9.9822 -28.9814 180)
		(property "Reference" "PC78"
			(at 0 0 180)
			(layer "F.SilkS")
			(hide yes)
			(effects
				(font
					(size 1.27 1.27)
				)
			)
		)
		(property "Value" "SCD1U50V3KX-GP"
			(at -0.0254 -2.0193 180)
			(unlocked yes)
			(layer "F.Fab")
			(hide yes)
			(effects
				(font
					(size 1.016 1.016)
					(thickness 0.1524)
				)
			)
		)
		(property "Device Type" "C603H36"
			(at -0.0254 -3.5433 180)
			(unlocked yes)
			(layer "F.Fab")
			(hide yes)
			(effects
				(font
					(size 1.016 1.016)
					(thickness 0.1524)
				)
			)
		)
		(duplicate_pad_numbers_are_jumpers no)
		(fp_line
			(start -0.4064 0)
			(end 0.4064 0)
			(stroke
				(width 0.2286)
				(type default)
			)
			(layer "F.SilkS")
		)
		(fp_rect
			(start -0.635 1.1811)
			(end 0.635 -1.1811)
			(stroke
				(width 0)
				(type default)
			)
			(fill no)
			(layer "F.CrtYd")
		)
		(fp_rect
			(start -0.635 1.1811)
			(end 0.635 -1.1811)
			(stroke
				(width 0)
				(type default)
			)
			(fill no)
			(layer "F.Fab")
		)
		(pad "1" smd custom
			(at 0 -0.6604 180)
			(size 0.19685 0.19685)
			(layers "F.Cu" "F.Mask" "F.Paste")
			(net "P1V0_VIN")
			(options
				(clearance outline)
				(anchor circle)
			)
			(primitives
				(gr_poly
					(pts
						(arc
							(start 0.508 -0.2921)
							(mid 0.478242 -0.363942)
							(end 0.4064 -0.3937)
						)
						(arc
							(start -0.4064 -0.3937)
							(mid -0.478242 -0.363942)
							(end -0.508 -0.2921)
						)
						(arc
							(start -0.508 0.2921)
							(mid -0.478242 0.363942)
							(end -0.4064 0.3937)
						)
						(arc
							(start 0.4064 0.3937)
							(mid 0.478242 0.363942)
							(end 0.508 0.2921)
						)
					)
					(width 0)
					(fill yes)
				)
			)
		)
		(pad "2" smd custom
			(at 0 0.6604 180)
			(size 0.19685 0.19685)
			(layers "F.Cu" "F.Mask" "F.Paste")
			(net "GND")
			(options
				(clearance outline)
				(anchor circle)
			)
			(primitives
				(gr_poly
					(pts
						(arc
							(start 0.508 -0.2921)
							(mid 0.478242 -0.363942)
							(end 0.4064 -0.3937)
						)
						(arc
							(start -0.4064 -0.3937)
							(mid -0.478242 -0.363942)
							(end -0.508 -0.2921)
						)
						(arc
							(start -0.508 0.2921)
							(mid -0.478242 0.363942)
							(end -0.4064 0.3937)
						)
						(arc
							(start 0.4064 0.3937)
							(mid 0.478242 0.363942)
							(end 0.508 0.2921)
						)
					)
					(width 0)
					(fill yes)
				)
			)
		)
	)
	(footprint ""
		(layer "F.Cu")
		(at 23.8506 -66.9036)
		(property "Reference" "PR23"
			(at 0 0 0)
			(layer "F.SilkS")
			(hide yes)
			(effects
				(font
					(size 1.27 1.27)
				)
			)
		)
		(property "Value" "0R2J-2-GP"
			(at 1.7907 -1.1176 0)
			(unlocked yes)
			(layer "F.Fab")
			(hide yes)
			(effects
				(font
					(size 1.016 1.016)
					(thickness 0.1524)
				)
			)
		)
		(property "Device Type" "R402H16"
			(at 1.7907 -2.6416 0)
			(unlocked yes)
			(layer "F.Fab")
			(hide yes)
			(effects
				(font
					(size 1.016 1.016)
					(thickness 0.1524)
				)
			)
		)
		(duplicate_pad_numbers_are_jumpers no)
		(fp_rect
			(start -0.381 0.8382)
			(end 0.381 -0.8382)
			(stroke
				(width 0)
				(type default)
			)
			(fill no)
			(layer "F.CrtYd")
		)
		(fp_rect
			(start -0.381 0.8382)
			(end 0.381 -0.8382)
			(stroke
				(width 0)
				(type default)
			)
			(fill no)
			(layer "F.Fab")
		)
		(pad "1" smd custom
			(at 0 -0.4318)
			(size 0.127 0.127)
			(layers "F.Cu" "F.Mask" "F.Paste")
			(net "VR_PVNN_PHASE")
			(options
				(clearance outline)
				(anchor circle)
			)
			(primitives
				(gr_poly
					(pts
						(arc
							(start -0.2032 -0.2794)
							(mid -0.239121 -0.264521)
							(end -0.254 -0.2286)
						)
						(arc
							(start -0.254 0.2286)
							(mid -0.239121 0.264521)
							(end -0.2032 0.2794)
						)
						(arc
							(start 0.2032 0.2794)
							(mid 0.239121 0.264521)
							(end 0.254 0.2286)
						)
						(arc
							(start 0.254 -0.2286)
							(mid 0.239121 -0.264521)
							(end 0.2032 -0.2794)
						)
					)
					(width 0)
					(fill yes)
				)
			)
		)
		(pad "2" smd custom
			(at 0 0.4318)
			(size 0.127 0.127)
			(layers "F.Cu" "F.Mask" "F.Paste")
			(net "VR_PVNN_BOOT_R")
			(options
				(clearance outline)
				(anchor circle)
			)
			(primitives
				(gr_poly
					(pts
						(arc
							(start -0.2032 -0.2794)
							(mid -0.239121 -0.264521)
							(end -0.254 -0.2286)
						)
						(arc
							(start -0.254 0.2286)
							(mid -0.239121 0.264521)
							(end -0.2032 0.2794)
						)
						(arc
							(start 0.2032 0.2794)
							(mid 0.239121 0.264521)
							(end 0.254 0.2286)
						)
						(arc
							(start 0.254 -0.2286)
							(mid 0.239121 -0.264521)
							(end 0.2032 -0.2794)
						)
					)
					(width 0)
					(fill yes)
				)
			)
		)
	)
	(footprint ""
		(layer "F.Cu")
		(at 114.046 -71.12 180)
		(property "Reference" "R230"
			(at 0 0 180)
			(layer "F.SilkS")
			(hide yes)
			(effects
				(font
					(size 1.27 1.27)
				)
			)
		)
		(property "Value" "4K7R2F-GP"
			(at 0.064008 -3.993896 180)
			(unlocked yes)
			(layer "F.Fab")
			(hide yes)
			(effects
				(font
					(size 1.016 1.016)
					(thickness 0.1524)
				)
			)
		)
		(property "Device Type" "R402H16"
			(at 0.064008 -5.517896 180)
			(unlocked yes)
			(layer "F.Fab")
			(hide yes)
			(effects
				(font
					(size 1.016 1.016)
					(thickness 0.1524)
				)
			)
		)
		(duplicate_pad_numbers_are_jumpers no)
		(fp_rect
			(start -0.381 0.8382)
			(end 0.381 -0.8382)
			(stroke
				(width 0)
				(type default)
			)
			(fill no)
			(layer "F.CrtYd")
		)
		(fp_rect
			(start -0.381 0.8382)
			(end 0.381 -0.8382)
			(stroke
				(width 0)
				(type default)
			)
			(fill no)
			(layer "F.Fab")
		)
		(pad "1" smd custom
			(at 0 -0.4318 180)
			(size 0.127 0.127)
			(layers "F.Cu" "F.Mask" "F.Paste")
			(net "P3V3_STBY")
			(options
				(clearance outline)
				(anchor circle)
			)
			(primitives
				(gr_poly
					(pts
						(arc
							(start -0.2032 -0.2794)
							(mid -0.239121 -0.264521)
							(end -0.254 -0.2286)
						)
						(arc
							(start -0.254 0.2286)
							(mid -0.239121 0.264521)
							(end -0.2032 0.2794)
						)
						(arc
							(start 0.2032 0.2794)
							(mid 0.239121 0.264521)
							(end 0.254 0.2286)
						)
						(arc
							(start 0.254 -0.2286)
							(mid 0.239121 -0.264521)
							(end 0.2032 -0.2794)
						)
					)
					(width 0)
					(fill yes)
				)
			)
		)
		(pad "2" smd custom
			(at 0 0.4318 180)
			(size 0.127 0.127)
			(layers "F.Cu" "F.Mask" "F.Paste")
			(net "CHA_1_SA1")
			(options
				(clearance outline)
				(anchor circle)
			)
			(primitives
				(gr_poly
					(pts
						(arc
							(start -0.2032 -0.2794)
							(mid -0.239121 -0.264521)
							(end -0.254 -0.2286)
						)
						(arc
							(start -0.254 0.2286)
							(mid -0.239121 0.264521)
							(end -0.2032 0.2794)
						)
						(arc
							(start 0.2032 0.2794)
							(mid 0.239121 0.264521)
							(end 0.254 0.2286)
						)
						(arc
							(start 0.254 -0.2286)
							(mid 0.239121 -0.264521)
							(end 0.2032 -0.2794)
						)
					)
					(width 0)
					(fill yes)
				)
			)
		)
	)
	(footprint ""
		(layer "F.Cu")
		(at 183.2102 -33.5026)
		(property "Reference" "PR142"
			(at 0 0 0)
			(layer "F.SilkS")
			(hide yes)
			(effects
				(font
					(size 1.27 1.27)
				)
			)
		)
		(property "Value" "0R2J-2-GP"
			(at 1.7907 -1.1176 0)
			(unlocked yes)
			(layer "F.Fab")
			(hide yes)
			(effects
				(font
					(size 1.016 1.016)
					(thickness 0.1524)
				)
			)
		)
		(property "Device Type" "R402H16"
			(at 1.7907 -2.6416 0)
			(unlocked yes)
			(layer "F.Fab")
			(hide yes)
			(effects
				(font
					(size 1.016 1.016)
					(thickness 0.1524)
				)
			)
		)
		(duplicate_pad_numbers_are_jumpers no)
		(fp_rect
			(start -0.381 0.8382)
			(end 0.381 -0.8382)
			(stroke
				(width 0)
				(type default)
			)
			(fill no)
			(layer "F.CrtYd")
		)
		(fp_rect
			(start -0.381 0.8382)
			(end 0.381 -0.8382)
			(stroke
				(width 0)
				(type default)
			)
			(fill no)
			(layer "F.Fab")
		)
		(pad "1" smd custom
			(at 0 -0.4318)
			(size 0.127 0.127)
			(layers "F.Cu" "F.Mask" "F.Paste")
			(net "VR_PVDDR_PNN_VRHOT#")
			(options
				(clearance outline)
				(anchor circle)
			)
			(primitives
				(gr_poly
					(pts
						(arc
							(start -0.2032 -0.2794)
							(mid -0.239121 -0.264521)
							(end -0.254 -0.2286)
						)
						(arc
							(start -0.254 0.2286)
							(mid -0.239121 0.264521)
							(end -0.2032 0.2794)
						)
						(arc
							(start 0.2032 0.2794)
							(mid 0.239121 0.264521)
							(end 0.254 0.2286)
						)
						(arc
							(start 0.254 -0.2286)
							(mid 0.239121 -0.264521)
							(end 0.2032 -0.2794)
						)
					)
					(width 0)
					(fill yes)
				)
			)
		)
		(pad "2" smd custom
			(at 0 0.4318)
			(size 0.127 0.127)
			(layers "F.Cu" "F.Mask" "F.Paste")
			(net "PVCCP_PVNN_VRHOT#")
			(options
				(clearance outline)
				(anchor circle)
			)
			(primitives
				(gr_poly
					(pts
						(arc
							(start -0.2032 -0.2794)
							(mid -0.239121 -0.264521)
							(end -0.254 -0.2286)
						)
						(arc
							(start -0.254 0.2286)
							(mid -0.239121 0.264521)
							(end -0.2032 0.2794)
						)
						(arc
							(start 0.2032 0.2794)
							(mid 0.239121 0.264521)
							(end 0.254 0.2286)
						)
						(arc
							(start 0.254 -0.2286)
							(mid 0.239121 -0.264521)
							(end 0.2032 -0.2794)
						)
					)
					(width 0)
					(fill yes)
				)
			)
		)
	)
	(footprint ""
		(layer "F.Cu")
		(at 74.041 -34.417 90)
		(property "Reference" "R112"
			(at 0 0 90)
			(layer "F.SilkS")
			(hide yes)
			(effects
				(font
					(size 1.27 1.27)
				)
			)
		)
		(property "Value" "10KR2F-2-GP"
			(at 0.064008 -3.993896 90)
			(unlocked yes)
			(layer "F.Fab")
			(hide yes)
			(effects
				(font
					(size 1.016 1.016)
					(thickness 0.1524)
				)
			)
		)
		(property "Device Type" "R402H16"
			(at 0.064008 -5.517896 90)
			(unlocked yes)
			(layer "F.Fab")
			(hide yes)
			(effects
				(font
					(size 1.016 1.016)
					(thickness 0.1524)
				)
			)
		)
		(duplicate_pad_numbers_are_jumpers no)
		(fp_rect
			(start -0.381 0.8382)
			(end 0.381 -0.8382)
			(stroke
				(width 0)
				(type default)
			)
			(fill no)
			(layer "F.CrtYd")
		)
		(fp_rect
			(start -0.381 0.8382)
			(end 0.381 -0.8382)
			(stroke
				(width 0)
				(type default)
			)
			(fill no)
			(layer "F.Fab")
		)
		(pad "1" smd custom
			(at 0 -0.4318 90)
			(size 0.127 0.127)
			(layers "F.Cu" "F.Mask" "F.Paste")
			(net "P3V3_CPU")
			(options
				(clearance outline)
				(anchor circle)
			)
			(primitives
				(gr_poly
					(pts
						(arc
							(start -0.2032 -0.2794)
							(mid -0.239121 -0.264521)
							(end -0.254 -0.2286)
						)
						(arc
							(start -0.254 0.2286)
							(mid -0.239121 0.264521)
							(end -0.2032 0.2794)
						)
						(arc
							(start 0.2032 0.2794)
							(mid 0.239121 0.264521)
							(end 0.254 0.2286)
						)
						(arc
							(start 0.254 -0.2286)
							(mid 0.239121 -0.264521)
							(end 0.2032 -0.2794)
						)
					)
					(width 0)
					(fill yes)
				)
			)
		)
		(pad "2" smd custom
			(at 0 0.4318 90)
			(size 0.127 0.127)
			(layers "F.Cu" "F.Mask" "F.Paste")
			(net "PU_PMU_GPE#")
			(options
				(clearance outline)
				(anchor circle)
			)
			(primitives
				(gr_poly
					(pts
						(arc
							(start -0.2032 -0.2794)
							(mid -0.239121 -0.264521)
							(end -0.254 -0.2286)
						)
						(arc
							(start -0.254 0.2286)
							(mid -0.239121 0.264521)
							(end -0.2032 0.2794)
						)
						(arc
							(start 0.2032 0.2794)
							(mid 0.239121 0.264521)
							(end 0.254 0.2286)
						)
						(arc
							(start 0.254 -0.2286)
							(mid 0.239121 -0.264521)
							(end 0.2032 -0.2794)
						)
					)
					(width 0)
					(fill yes)
				)
			)
		)
	)
)
